FILE_TYPE = CONNECTIVITY;
{Allegro Design Entry HDL 17.2-2016 S081 (4005846) 1/11/2022}
"PAGE_NUMBER" = 252;
0"NC";
1"P3V3_AUX\g";
2"P3V3_AUX\g";
3"P3V3_AUX\g";
4"PVNN_TERM_CPU0\g";
5"P3V3_AUX\g";
6"P3V3_AUX\g";
7"PVCCIN_CPU0\g";
8"PVCCFA_EHV_FIVRA_CPU0\g";
9"P12V_AUX\g";
10"P3V3_AUX\g";
11"GND\g";
12"GND\g";
13"GND\g";
14"GND\g";
15"GND\g";
16"GND\g";
17"GND\g";
18"GND\g";
19"GND\g";
20"GND\g";
21"GND\g";
22"GND\g";
23"GND\g";
24"GND\g";
25"GND\g";
26"GND\g";
27"GND\g";
28"GND\g";
29"GND\g";
30"GND\g";
31"PVCCIN_CPU0_PWM1";
32"PVCCIN_CPU0_IMON2";
33"PVCCIN_CPU0_IMON1";
34"PVCCIN_CPU0_VREF";
35"PVCCIN_CPU0_PWM5";
36"PVCCIN_CPU0_PWM6";
37"PVCCIN_CPU0_IMON6";
38"PVCCIN_CPU0_PWM4";
39"PVCCIN_CPU0_IMON4";
40"PVCCFA_EHV_FIVRA_CPU0_IMON3";
41"PVCCFA_EHV_FIVRA_CPU0_PWM3";
42"PVCCIN_CPU0_PWM3";
43"IRQ_PVCCIN_CPU0_VRHOT_R_N";
44"VSENSE_PVCCFA_EHV_FIVRA_CPU0_DN";
45"PVCCIN_CPU0_VR_FAULT";
46"FM_PVCCFA_EHV_FIVRA_CPU0_EN";
47"PVCCIN_CPU0_PIN_ALERT";
48"IRQ_PVCCIN_CPU0_VRHOT_N";
49"IRQ_PSYS_CRIT_N";
50"VSENSE_PVCCIN_CPU0_DN";
51"SH_PVCCIN_CPU0_R";
52"NC_PVCCIN_CPU0_SMB_ALERT";
53"SMB_DIO_PVCCIN_CPU0";
54"SMB_CLK_PVCCIN_CPU0";
55"PVCCIN_CPU0_VCC";
56"PVCCIN_CPU0_PWM2";
57"PVCCIN_CPU0_PWM7";
58"PVCCIN_CPU0_IMON7";
59"PVCCIN_CPU0_PWM8";
60"PVCCIN_CPU0_IMON8";
61"PVCCFA_EHV_FIVRA_CPU0_PWM4";
62"PVCCFA_EHV_FIVRA_CPU0_IMON4";
63"SVID_CLK0_CPU0_R"CDS_PHYS_NET_NAME"SVID_CLK0_CPU0_R";
64"SVID_ALERT0_CPU0_R_N"CDS_PHYS_NET_NAME"SVID_ALERT0_CPU0_R_N";
65"SVID_DIO0_CPU0_R"CDS_PHYS_NET_NAME"SVID_DIO0_CPU0_R";
66"PVCCFA_EHV_FIVRA_CPU0_BTSEN";
67"PVCCFA_EHV_FIVRA_CPU0_PWM2";
68"PVCCFA_EHV_FIVRA_CPU0_IMON2";
69"PVCCFA_EHV_FIVRA_CPU0_PWM1";
70"PVCCFA_EHV_FIVRA_CPU0_IMON1";
71"PVCCIN_CPU0_IMON5";
72"PVCCIN_CPU0_IMON3";
73"PWRGD_PVCCIN_CPU0_R";
74"PVCCIN_CPU0_EN_R";
75"SVID_DIO_PVCCIN_CPU0_R";
76"SVID_CLK_PVCCIN_CPU0_R";
77"SVID_ALERT_PVCCIN_CPU0_R";
78"PVCCIN_CPU0_ATSEN";
79"SH_PVCCFA_EHV_FIVRA_CPU0_R";
80"PVCCIN_CPU0_VIN_CSNIN";
81"PVCCFA_EHV_FIVRA_CPU0_EN_R";
82"PWRGD_PVCCFA_EHV_FIVRA_CPU0_R";
83"PVCCIN_CPU0_CSPIN";
84"SH_PVCCFA_EHV_FIVRA_CPU0";
85"SH_PVCCIN_CPU0";
86"PWRGD_PVCCFA_EHV_FIVRA_CPU0";
87"PWRGD_PVCCIN_CPU0";
88"FM_PVCCIN_CPU0_EN";
89"SMB_VR_3V3AUX_SDA_R3";
90"VSENSE_PVCCIN_CPU0_DP";
91"SVID_ALERT0_CPU0_R_N";
92"SVID_DIO0_CPU0_R";
93"SVID_CLK0_CPU0_R";
94"SMB_VR_3V3AUX_SCL_R3";
95"VSENSE_PVCCFA_EHV_FIVRA_CPU0_DP";
96"PVCCIN_CPU0_ADDR";
97"PVCCIN_CPU0_VREF";
%"Q_RES"
"1","(-5200,1100)","0","pure_quanta","I10";
;
PART_NUMBER"CS00002JB13"
MATERIAL"CHIP"
TOLERANCE"5%"
VALUE"0"
PACK_TYPE"0402LF"
WATTAGE"1/16W"
LOCATION"PR156"
CDS_LIB"pure_quanta"
LOCATION"PR156"
$SEC"1"
CDS_SEC"1";
"B"
$PN"2"80;
"A"
$PN"1"9;
%"Q_RES"
"1","(-5200,1200)","0","pure_quanta","I11";
;
PART_NUMBER"CS00002JB13"
TOLERANCE"5%"
MATERIAL"EMPTY"
VALUE"0"
PACK_TYPE"0402LF"
LOCATION"PR157"
WATTAGE"1/16W"
CDS_LIB"pure_quanta"
LOCATION"PR157"
$SEC"1"
CDS_SEC"1";
"B"
$PN"2"83;
"A"
$PN"1"9;
%"UNIVERSAL_GND"
"1","(-125,1200)","0","logical_power","I114";
;
CDS_LIB"logical_power"
HDL_POWER"GND";
"A"15;
%"Q_CAP"
"1","(-125,1450)","0","pure_quanta","I116";
;
PART_NUMBER"TMP_QCH14706KB18"
VALUE"470PF"
PACK_TYPE"0402"
MATERIAL"X7R"
VOLTAGE"50V"
TOLERANCE"10%"
LOCATION"PC100"
CDS_LIB"pure_quanta"
LOCATION"PC100"
$SEC"1"
CDS_SEC"1";
"B"
$PN"2"15;
"A"
$PN"1"66;
%"VCC15"
"1","(-5475,1325)","0","logical_power","I12";
;
HDL_POWER"P12V_AUX"
CDS_LIB"logical_power";
"A"9;
%"UNIVERSAL_GND"
"1","(550,1175)","0","logical_power","I120";
;
CDS_LIB"logical_power"
HDL_POWER"GND";
"A"14;
%"Q_RES"
"2","(550,1425)","0","pure_quanta","I121";
;
PART_NUMBER"CS31002FB08"
MATERIAL"EMPTY"
WATTAGE"1/16W"
TOLERANCE"1%"
VALUE"10K"
PACK_TYPE"0402LF"
LOCATION"PR451"
CDS_LIB"pure_quanta"
$SEC"1"
CDS_SEC"1";
"A"
$PN"1"66;
"B"
$PN"2"14;
%"Q_RES"
"1","(950,1900)","0","pure_quanta","I123";
;
PART_NUMBER"CS04992FB07"
TOLERANCE"1%"
MATERIAL"EMPTY"
WATTAGE"1/16W"
PACK_TYPE"0402LF"
VALUE"49.9"
LOCATION"R2382"
CDS_LIB"pure_quanta"
$SEC"1"
CDS_SEC"1";
"B"
$PN"2"4;
"A"
$PN"1"64;
%"Q_RES"
"1","(950,2200)","0","pure_quanta","I124";
;
PART_NUMBER"CS11002FB07"
PACK_TYPE"0402LF"
WATTAGE"1/16W"
TOLERANCE"1%"
MATERIAL"CHIP"
VALUE"100"
LOCATION"R2590"
CDS_LIB"pure_quanta"
$SEC"1"
CDS_SEC"1";
"B"
$PN"2"4;
"A"
$PN"1"65;
%"Q_RES"
"1","(950,2050)","0","pure_quanta","I125";
;
PART_NUMBER"CS04992FB07"
VALUE"49.9"
TOLERANCE"1%"
MATERIAL"CHIP"
WATTAGE"1/16W"
PACK_TYPE"0402LF"
LOCATION"R2381"
CDS_LIB"pure_quanta"
$SEC"1"
CDS_SEC"1";
"B"
$PN"2"4;
"A"
$PN"1"63;
%"UNIVERSAL_GND"
"1","(750,2375)","0","logical_power","I126";
;
CDS_LIB"logical_power"
HDL_POWER"GND";
"A"13;
%"Q_CAP"
"1","(750,2675)","0","pure_quanta","I127";
;
PART_NUMBER"CH610KME907"
VALUE"10UF"
VOLTAGE"4V"
TOLERANCE"20%"
MATERIAL"EMPTY"
PACK_TYPE"C0603"
LOCATION"C3270"
CDS_LIB"pure_quanta"
LOCATION"C3270"
$SEC"1"
CDS_SEC"1";
"B"
$PN"2"13;
"A"
$PN"1"4;
%"Q_CAP"
"1","(1075,2650)","0","pure_quanta","I128";
;
PART_NUMBER"CH4106K1B01"
VALUE"100NF"
VOLTAGE"50V"
PACK_TYPE"C0402"
MATERIAL"X7R"
TOLERANCE"10%"
LOCATION"C3271"
CDS_LIB"pure_quanta"
LOCATION"C3271"
$SEC"1"
CDS_SEC"1";
"B"
$PN"2"13;
"A"
$PN"1"4;
%"VCC15"
"1","(1475,2950)","0","logical_power","I129";
;
HDL_POWER"PVNN_TERM_CPU0"
CDS_LIB"logical_power";
"A"4;
%"VCC15"
"1","(-5425,2000)","0","logical_power","I13";
;
HDL_POWER"P3V3_AUX"
CDS_LIB"logical_power";
"A"2;
%"UNIVERSAL_GND"
"1","(-650,5675)","3","logical_power","I130";
;
CDS_LIB"logical_power"
HDL_POWER"GND";
"A"12;
%"UNIVERSAL_GND"
"1","(-650,6150)","3","logical_power","I132";
;
CDS_LIB"logical_power"
HDL_POWER"GND";
"A"11;
%"Q_RES"
"1","(-775,6550)","0","pure_quanta","I133";
;
PART_NUMBER"CS-1002FB04"
VALUE"1"
MATERIAL"CHIP"
WATTAGE"1/16W"
TOLERANCE"1%"
PACK_TYPE"0402LF"
LOCATION"PR176"
CDS_LIB"pure_quanta"
LOCATION"PR176"
$SEC"1"
CDS_SEC"1";
"B"
$PN"2"3;
"A"
$PN"1"55;
%"VCC15"
"1","(-300,6675)","0","logical_power","I134";
;
HDL_POWER"P3V3_AUX"
CDS_LIB"logical_power";
"A"3;
%"Q_CAP"
"1","(-1825,6350)","0","pure_quanta","I136";
;
PART_NUMBER"CH4104K1B00"
VALUE"0.1UF"
VOLTAGE"25V"
TOLERANCE"10%"
MATERIAL"EMPTY"
PACK_TYPE"0402"
LOCATION"PC2361"
CDS_LIB"pure_quanta"
$SEC"1"
CDS_SEC"1";
"B"
$PN"2"11;
"A"
$PN"1"55;
%"Q_RES"
"1","(-6025,2925)","0","pure_quanta","I15";
;
PART_NUMBER"CS11002FB07"
PACK_TYPE"0402LF"
MATERIAL"CHIP"
TOLERANCE"1%"
WATTAGE"1/16W"
VALUE"100"
LOCATION"PR586"
CDS_LIB"pure_quanta"
$SEC"1"
CDS_SEC"1";
"B"
$PN"2"29;
"A"
$PN"1"44;
%"VCC15"
"1","(-6100,2550)","0","logical_power","I16";
;
HDL_POWER"P3V3_AUX"
CDS_LIB"logical_power";
"A"10;
%"Q_RES"
"1","(-5675,2300)","0","pure_quanta","I17";
;
PART_NUMBER"CS00002JB13"
VALUE"0"
WATTAGE"1/16W"
MATERIAL"CHIP"
PACK_TYPE"0402LF"
TOLERANCE"5%"
LOCATION"R2376"
CDS_LIB"pure_quanta"
$SEC"1"
CDS_SEC"1";
"B"
$PN"2"47;
"A"
$PN"1"49;
%"Q_RES"
"1","(-5250,2450)","0","pure_quanta","I19";
;
PART_NUMBER"CS21002FB06"
PACK_TYPE"0402LF"
VALUE"1K"
TOLERANCE"1%"
LOCATION"R2375"
CDS_LIB"pure_quanta"
WATTAGE"1/16W"
MATERIAL"CHIP"
$SEC"1"
CDS_SEC"1";
"B"
$PN"2"47;
"A"
$PN"1"10;
%"Q_RES"
"1","(-5250,2550)","0","pure_quanta","I20";
;
PART_NUMBER"CS21002FB06"
WATTAGE"1/16W"
PACK_TYPE"0402LF"
TOLERANCE"1%"
VALUE"1K"
MATERIAL"CHIP"
LOCATION"R2589"
CDS_LIB"pure_quanta"
$SEC"1"
CDS_SEC"1";
"B"
$PN"2"45;
"A"
$PN"1"10;
%"UNIVERSAL_GND"
"1","(-5550,2825)","0","logical_power","I21";
;
CDS_LIB"logical_power"
HDL_POWER"GND";
"A"29;
%"VCC15"
"1","(-5400,2950)","0","logical_power","I22";
;
HDL_POWER"P3V3_AUX"
CDS_LIB"logical_power";
"A"1;
%"Q_RES"
"1","(-5250,2850)","0","pure_quanta","I23";
;
PART_NUMBER"CS21002FB06"
VALUE"1K"
PACK_TYPE"0402LF"
TOLERANCE"1%"
LOCATION"R2373"
MATERIAL"CHIP"
WATTAGE"1/16W"
CDS_LIB"pure_quanta"
$SEC"1"
CDS_SEC"1";
"B"
$PN"2"43;
"A"
$PN"1"1;
%"Q_SHORT"
"1","(-5825,3450)","0","pure_quanta","I24";
;
PART_NUMBER"SHORT6"
MATERIAL"EMPTY"
PACK_TYPE"SM"
LOCATION"PJ53"
CDS_LIB"pure_quanta"
NEEDS_NO_SIZE"TRUE"
LOCATION"PJ53"
$SEC"1"
CDS_SEC"1";
"1"
$PN"1"95;
"2"
$PN"2"84;
%"Q_RES"
"1","(-5750,3600)","0","pure_quanta","I25";
;
PART_NUMBER"CS11002FB07"
WATTAGE"1/16W"
MATERIAL"CHIP"
PACK_TYPE"0402LF"
VALUE"100"
TOLERANCE"1%"
LOCATION"PR587"
CDS_LIB"pure_quanta"
$SEC"1"
CDS_SEC"1";
"B"
$PN"2"8;
"A"
$PN"1"95;
%"Q_RES"
"1","(-5800,4025)","0","pure_quanta","I26";
;
PART_NUMBER"CS11002FB07"
WATTAGE"1/16W"
VALUE"100"
TOLERANCE"1%"
MATERIAL"CHIP"
PACK_TYPE"0402LF"
LOCATION"PR527"
CDS_LIB"pure_quanta"
$SEC"1"
CDS_SEC"1";
"B"
$PN"2"28;
"A"
$PN"1"50;
%"VCC15"
"1","(-5250,3750)","0","logical_power","I27";
;
HDL_POWER"PVCCFA_EHV_FIVRA_CPU0"
CDS_LIB"logical_power";
"A"8;
%"UNIVERSAL_GND"
"1","(-5275,3925)","0","logical_power","I28";
;
CDS_LIB"logical_power"
HDL_POWER"GND";
"A"28;
%"CONN3_210HP1030BR1"
"1","(-6525,5600)","4","pure_quanta","I32";
;
PART_NUMBER"DFHD03MS213"
LOCATION"PJP1"
SEC_TYPE""
NEEDS_NO_SIZE"TRUE"
PART_TYPE"THLF"
MATERIAL"IO"
VALUE"CONN3_210-HP1-030BR1"
CDS_LMAN_SYM_OUTLINE"-50,100,50,-100"
CDS_LIB"pure_quanta"
SEC"1";
"1"
$PN"1"94;
"2"
$PN"2"27;
"3"
$PN"3"89;
%"UNIVERSAL_GND"
"1","(-6075,5600)","1","logical_power","I34";
;
CDS_LIB"logical_power"
HDL_POWER"GND";
"A"27;
%"Q_SHORT"
"1","(-5825,4550)","0","pure_quanta","I37";
;
PART_NUMBER"SHORT6"
MATERIAL"EMPTY"
PACK_TYPE"SM"
LOCATION"PJ47"
NEEDS_NO_SIZE"TRUE"
CDS_LIB"pure_quanta"
LOCATION"PJ47"
$SEC"1"
CDS_SEC"1";
"1"
$PN"1"90;
"2"
$PN"2"85;
%"Q_RES"
"1","(-5750,4700)","0","pure_quanta","I38";
;
PART_NUMBER"CS11002FB07"
VALUE"100"
WATTAGE"1/16W"
MATERIAL"CHIP"
TOLERANCE"1%"
PACK_TYPE"0402LF"
LOCATION"PR531"
CDS_LIB"pure_quanta"
$SEC"1"
CDS_SEC"1";
"B"
$PN"2"7;
"A"
$PN"1"90;
%"VCC15"
"1","(-5250,4850)","0","logical_power","I39";
;
HDL_POWER"PVCCIN_CPU0"
CDS_LIB"logical_power";
"A"7;
%"Q_RES"
"1","(-5125,5550)","0","pure_quanta","I40";
;
PART_NUMBER"CS24702JB10"
MATERIAL"EMPTY"
TOLERANCE"5%"
VALUE"4.7K"
LOCATION"R1713"
CDS_LIB"pure_quanta"
PACK_TYPE"0402LF"
WATTAGE"1/16W"
LOCATION"R1713"
$SEC"1"
CDS_SEC"1";
"B"
$PN"2"5;
"A"
$PN"1"94;
%"Q_RES"
"1","(-5125,5800)","0","pure_quanta","I41";
;
PART_NUMBER"CS00002JB13"
PACK_TYPE"0402LF"
WATTAGE"1/16W"
MATERIAL"CHIP"
TOLERANCE"5%"
VALUE"0"
LOCATION"R2370"
CDS_LIB"pure_quanta"
LOCATION"R2370"
$SEC"1"
CDS_SEC"1";
"B"
$PN"2"77;
"A"
$PN"1"91;
%"Q_RES"
"1","(-5125,5600)","0","pure_quanta","I42";
;
PART_NUMBER"CS24702JB10"
WATTAGE"1/16W"
PACK_TYPE"0402LF"
MATERIAL"EMPTY"
TOLERANCE"5%"
VALUE"4.7K"
LOCATION"R1712"
CDS_LIB"pure_quanta"
LOCATION"R1712"
$SEC"1"
CDS_SEC"1";
"B"
$PN"2"5;
"A"
$PN"1"89;
%"Q_RES"
"1","(-5125,5950)","0","pure_quanta","I43";
;
PART_NUMBER"CS00002JB13"
VALUE"0"
TOLERANCE"5%"
PACK_TYPE"0402LF"
WATTAGE"1/16W"
MATERIAL"CHIP"
LOCATION"R2369"
CDS_LIB"pure_quanta"
LOCATION"R2369"
$SEC"1"
CDS_SEC"1";
"B"
$PN"2"75;
"A"
$PN"1"92;
%"Q_RES"
"1","(-5125,6100)","0","pure_quanta","I44";
;
PART_NUMBER"CS11502FB07"
WATTAGE"1/16W"
PACK_TYPE"0402LF"
TOLERANCE"1%"
VALUE"150"
MATERIAL"CHIP"
LOCATION"R2368"
CDS_LIB"pure_quanta"
LOCATION"R2368"
$SEC"1"
CDS_SEC"1";
"B"
$PN"2"76;
"A"
$PN"1"93;
%"VCC15"
"1","(-5550,6800)","0","logical_power","I47";
;
HDL_POWER"P3V3_AUX"
CDS_LIB"logical_power";
"A"6;
%"Q_RES"
"1","(-5125,6400)","0","pure_quanta","I48";
;
PART_NUMBER"CS00002JB13"
VALUE"0"
WATTAGE"1/16W"
TOLERANCE"5%"
PACK_TYPE"0402LF"
MATERIAL"CHIP"
LOCATION"R2591"
CDS_LIB"pure_quanta"
LOCATION"R2591"
$SEC"1"
CDS_SEC"1";
"B"
$PN"2"74;
"A"
$PN"1"88;
%"Q_RES"
"1","(-5125,6550)","0","pure_quanta","I49";
;
PART_NUMBER"CS00002JB13"
VALUE"0"
TOLERANCE"5%"
MATERIAL"CHIP"
WATTAGE"1/16W"
PACK_TYPE"0402LF"
LOCATION"R2366"
CDS_LIB"pure_quanta"
LOCATION"R2366"
$SEC"1"
CDS_SEC"1";
"B"
$PN"2"73;
"A"
$PN"1"87;
%"Q_RES"
"1","(-6050,1450)","0","pure_quanta","I5";
;
PART_NUMBER"CS32802FB05"
VALUE"28K"
TOLERANCE"1%"
PACK_TYPE"0402LF"
WATTAGE"1/16W"
MATERIAL"EMPTY"
LOCATION"PR159"
CDS_LIB"pure_quanta"
LOCATION"PR159"
$SEC"1"
CDS_SEC"1";
"B"
$PN"2"96;
"A"
$PN"1"97;
%"Q_RES"
"1","(-5125,6700)","0","pure_quanta","I50";
;
PART_NUMBER"CS21002FB06"
TOLERANCE"1%"
VALUE"1K"
WATTAGE"1/16W"
MATERIAL"CHIP"
PACK_TYPE"0402LF"
LOCATION"R2365"
CDS_LIB"pure_quanta"
LOCATION"R2365"
$SEC"1"
CDS_SEC"1";
"B"
$PN"2"73;
"A"
$PN"1"6;
%"Q_RES"
"2","(-4750,900)","0","pure_quanta","I51";
;
PART_NUMBER"CS00002JB13"
TOLERANCE"5%"
WATTAGE"1/16W"
MATERIAL"CHIP"
VALUE"0"
PACK_TYPE"0402LF"
LOCATION"PR158"
CDS_LIB"pure_quanta"
LOCATION"PR158"
$SEC"1"
CDS_SEC"1";
"A"
$PN"1"83;
"B"
$PN"2"26;
%"UNIVERSAL_GND"
"1","(-4425,600)","0","logical_power","I52";
;
CDS_LIB"logical_power"
HDL_POWER"GND";
"A"26;
%"Q_CAP"
"1","(-4425,900)","0","pure_quanta","I53";
;
PART_NUMBER"CH4104K1B00"
TOLERANCE"10%"
PACK_TYPE"0402"
VOLTAGE"25V"
VALUE"0.1UF"
MATERIAL"EMPTY"
LOCATION"PC329"
CDS_LIB"pure_quanta"
LOCATION"PC329"
$SEC"1"
CDS_SEC"1";
"B"
$PN"2"26;
"A"
$PN"1"83;
%"Q_RES"
"1","(-4950,1900)","0","pure_quanta","I54";
;
PART_NUMBER"CS21002FB06"
MATERIAL"CHIP"
VALUE"1K"
WATTAGE"1/16W"
PACK_TYPE"0402LF"
TOLERANCE"1%"
LOCATION"R2377"
CDS_LIB"pure_quanta"
LOCATION"R2377"
$SEC"1"
CDS_SEC"1";
"B"
$PN"2"82;
"A"
$PN"1"2;
%"Q_RES"
"1","(-4950,1750)","0","pure_quanta","I55";
;
PART_NUMBER"CS00002JB13"
PACK_TYPE"0402LF"
MATERIAL"CHIP"
WATTAGE"1/16W"
TOLERANCE"5%"
VALUE"0"
LOCATION"R2379"
CDS_LIB"pure_quanta"
LOCATION"R2379"
$SEC"1"
CDS_SEC"1";
"B"
$PN"2"82;
"A"
$PN"1"86;
%"Q_RES"
"1","(-4950,2150)","0","pure_quanta","I56";
;
PART_NUMBER"CS00002JB13"
MATERIAL"CHIP"
WATTAGE"1/16W"
VALUE"0"
PACK_TYPE"0402LF"
TOLERANCE"5%"
$LOCATION"R4216"
CDS_LIB"pure_quanta"
CDS_LOCATION"R4216"
$SEC"1"
CDS_SEC"1";
"B"
$PN"2"81;
"A"
$PN"1"46;
%"Q_CAP"
"2","(-4150,1900)","0","pure_quanta","I57";
;
PART_NUMBER"TMP_QCH21006JB10"
VALUE"1000PF"
VOLTAGE"50V"
MATERIAL"EMPTY"
TOLERANCE"5%"
PACK_TYPE"0402"
LOCATION"C3269"
CDS_LIB"pure_quanta"
LOCATION"C3269"
$SEC"1"
CDS_SEC"1";
"A"
$PN"1"82;
"B"
$PN"2"23;
%"Q_CAP"
"2","(-4150,2025)","0","pure_quanta","I58";
;
PART_NUMBER"TMP_QCH21006JB10"
VALUE"1000PF"
VOLTAGE"50V"
TOLERANCE"5%"
MATERIAL"X7R"
PACK_TYPE"0402"
LOCATION"C3268"
CDS_LIB"pure_quanta"
LOCATION"C3268"
$SEC"1"
CDS_SEC"1";
"A"
$PN"1"81;
"B"
$PN"2"22;
%"UNIVERSAL_GND"
"1","(-3700,575)","0","logical_power","I59";
;
CDS_LIB"logical_power"
HDL_POWER"GND";
"A"25;
%"Q_RES"
"2","(-4050,900)","0","pure_quanta","I60";
;
PART_NUMBER"CS21002FB06"
PACK_TYPE"0402LF"
WATTAGE"1/16W"
TOLERANCE"1%"
VALUE"1K"
MATERIAL"EMPTY"
LOCATION"PR166"
CDS_LIB"pure_quanta"
LOCATION"PR166"
$SEC"1"
CDS_SEC"1";
"A"
$PN"1"80;
"B"
$PN"2"25;
%"Q_CAP"
"1","(-3700,900)","0","pure_quanta","I61";
;
PART_NUMBER"CH4104K1B00"
TOLERANCE"10%"
VOLTAGE"25V"
VALUE"0.1UF"
MATERIAL"X7R"
PACK_TYPE"0402"
LOCATION"PC330"
CDS_LIB"pure_quanta"
LOCATION"PC330"
$SEC"1"
CDS_SEC"1";
"B"
$PN"2"25;
"A"
$PN"1"80;
%"UNIVERSAL_GND"
"1","(-3500,875)","0","logical_power","I62";
;
CDS_LIB"logical_power"
HDL_POWER"GND";
"A"24;
%"RAA229126GNPHA0"
"1","(-2725,3800)","0","pure_quanta","I63";
;
PART_NUMBER"AL229126000"
VALUE"RAA229126GNP#HA0"
PART_TYPE"SMLF"
MATERIAL"IC"
LOCATION"PU14"
NEEDS_NO_SIZE"TRUE"
CDS_LMAN_SYM_OUTLINE"-550,2850,500,-2850"
CDS_LIB"pure_quanta"
SEC_TYPE""
SEC"1";
"CS10"
$PN"28"32;
"PWM10"
$PN"11"56;
"CS9"
$PN"29"72;
"PWM9"
$PN"10"42;
"CS8"
$PN"30"39;
"PWM8"
$PN"9"38;
"CS7"
$PN"31"71;
"PWM7"
$PN"8"35;
"CS0"
$PN"38"70;
"PWM0"
$PN"1"69;
"TEMP0"
$PN"43"78;
"ADDR_CFG"
$PN"42"96;
"TH_GND"
$PN"TH"24;
"CFP"
$PN"41"45;
"CS2"
$PN"36"40;
"PWM2"
$PN"3"41;
"CS3"
$PN"35"62;
"PWM3"
$PN"4"61;
"PWM11"
$PN"12"31;
"CS1"
$PN"37"68;
"RGND1"
$PN"39"44;
"VSEN1"
$PN"40"79;
"NPINALERT||NPSYS_CRIT \B"
$PN"19"47;
"TEMP1||ISYS"
$PN"44"66;
"VINSEN||VSYS"
$PN"46"80;
"VMON||IINSEN||VSYS||ISYS"
$PN"45"83;
"VCCS"
$PN"48"34;
"PWM6"
$PN"7"36;
"PG0"
$PN"16"73;
"PWM1"
$PN"2"67;
"VSEN0"
$PN"25"51;
"PWM5"
$PN"6"57;
"PWM4"
$PN"5"59;
"PMSDA"
$PN"13"53;
"RGND0"
$PN"26"50;
"EN0"
$PN"17"74;
"NPMALERT \B"
$PN"15"52;
"SVCLK"
$PN"21"76;
"PG1"
$PN"20"82;
"CS4"
$PN"34"60;
"CS5"
$PN"33"58;
"NVRHOT \B"
$PN"18"48;
"NSVALERT \B"
$PN"23"77;
"CS6"
$PN"32"37;
"SVDATA"
$PN"22"75;
"PMSCL"
$PN"14"54;
"EN1"
$PN"24"81;
"VCC"
$PN"47"55;
"CS11"
$PN"27"33;
%"UNIVERSAL_GND"
"1","(-3450,1900)","1","logical_power","I64";
;
CDS_LIB"logical_power"
HDL_POWER"GND";
"A"23;
%"UNIVERSAL_GND"
"1","(-3450,2025)","1","logical_power","I65";
;
CDS_LIB"logical_power"
HDL_POWER"GND";
"A"22;
%"Q_RES"
"1","(-4600,2700)","0","pure_quanta","I66";
;
PART_NUMBER"CS00002JB13"
VALUE"0"
WATTAGE"1/16W"
TOLERANCE"5%"
MATERIAL"CHIP"
PACK_TYPE"0402LF"
LOCATION"R4593"
CDS_LIB"pure_quanta"
$SEC"1"
CDS_SEC"1";
"B"
$PN"2"48;
"A"
$PN"1"43;
%"Q_CAP"
"1","(-4275,3275)","0","pure_quanta","I67";
;
PART_NUMBER"TMP_QCH2336K1B12"
VALUE"3300PF"
VOLTAGE"50V"
TOLERANCE"10%"
MATERIAL"X7R"
PACK_TYPE"0402"
LOCATION"PC594"
CDS_LIB"pure_quanta"
LOCATION"PC594"
$SEC"1"
CDS_SEC"1";
"B"
$PN"2"44;
"A"
$PN"1"79;
%"Q_RES"
"1","(-4725,3450)","0","pure_quanta","I68";
;
PART_NUMBER"CS00002JB13"
MATERIAL"CHIP"
WATTAGE"1/16W"
PACK_TYPE"0402LF"
VALUE"0"
TOLERANCE"5%"
LOCATION"PR345"
CDS_LIB"pure_quanta"
LOCATION"PR345"
$SEC"1"
CDS_SEC"1";
"B"
$PN"2"79;
"A"
$PN"1"84;
%"UNIVERSAL_GND"
"1","(-1800,900)","0","logical_power","I69";
;
CDS_LIB"logical_power"
HDL_POWER"GND";
"A"21;
%"Q_CAP"
"1","(-1800,1150)","0","pure_quanta","I70";
;
PART_NUMBER"TMP_QCH14706KB18"
VOLTAGE"50V"
TOLERANCE"10%"
PACK_TYPE"0402"
MATERIAL"X7R"
VALUE"470PF"
LOCATION"PC336"
CDS_LIB"pure_quanta"
LOCATION"PC336"
$SEC"1"
CDS_SEC"1";
"B"
$PN"2"21;
"A"
$PN"1"78;
%"UNIVERSAL_GND"
"1","(-1175,900)","0","logical_power","I71";
;
CDS_LIB"logical_power"
HDL_POWER"GND";
"A"20;
%"Q_RES"
"2","(-1175,1150)","0","pure_quanta","I72";
;
PART_NUMBER"CS31002FB08"
WATTAGE"1/16W"
PACK_TYPE"0402LF"
TOLERANCE"1%"
VALUE"10K"
MATERIAL"EMPTY"
LOCATION"PR400"
CDS_LIB"pure_quanta"
$SEC"1"
CDS_SEC"1";
"A"
$PN"1"78;
"B"
$PN"2"20;
%"Q_RES"
"1","(-1725,2675)","0","pure_quanta","I73";
;
PART_NUMBER"CS00002JB13"
VALUE"0"
TOLERANCE"5%"
MATERIAL"EMPTY"
PACK_TYPE"0402LF"
WATTAGE"1/16W"
LOCATION"PR4218"
CDS_LIB"pure_quanta"
$SEC"1"
CDS_SEC"1";
"B"
$PN"2"19;
"A"
$PN"1"40;
%"Q_RES"
"1","(-1725,2975)","0","pure_quanta","I74";
;
PART_NUMBER"CS00002JB13"
PACK_TYPE"0402LF"
WATTAGE"1/16W"
VALUE"0"
TOLERANCE"5%"
MATERIAL"EMPTY"
LOCATION"PR4217"
CDS_LIB"pure_quanta"
$SEC"1"
CDS_SEC"1";
"B"
$PN"2"18;
"A"
$PN"1"62;
%"UNIVERSAL_GND"
"1","(-1100,2600)","0","logical_power","I75";
;
CDS_LIB"logical_power"
HDL_POWER"GND";
"A"19;
%"UNIVERSAL_GND"
"1","(-1100,2900)","0","logical_power","I76";
;
CDS_LIB"logical_power"
HDL_POWER"GND";
"A"18;
%"Q_RES"
"1","(-4775,4550)","0","pure_quanta","I77";
;
PART_NUMBER"CS00002JB13"
VALUE"0"
TOLERANCE"5%"
MATERIAL"CHIP"
PACK_TYPE"0402LF"
WATTAGE"1/16W"
LOCATION"PR170"
CDS_LIB"pure_quanta"
LOCATION"PR170"
$SEC"1"
CDS_SEC"1";
"B"
$PN"2"51;
"A"
$PN"1"85;
%"Q_RES"
"1","(-4800,5250)","0","pure_quanta","I78";
;
PART_NUMBER"CS03322FB03"
VALUE"33.2"
MATERIAL"CHIP"
WATTAGE"1/16W"
PACK_TYPE"0402LF"
TOLERANCE"1%"
LOCATION"R2372"
CDS_LIB"pure_quanta"
LOCATION"R2372"
$SEC"1"
CDS_SEC"1";
"B"
$PN"2"53;
"A"
$PN"1"89;
%"Q_CAP"
"1","(-4325,4375)","0","pure_quanta","I79";
;
PART_NUMBER"TMP_QCH2336K1B12"
PACK_TYPE"0402"
VOLTAGE"50V"
TOLERANCE"10%"
MATERIAL"X7R"
VALUE"3300PF"
LOCATION"PC331"
CDS_LIB"pure_quanta"
LOCATION"PC331"
$SEC"1"
CDS_SEC"1";
"B"
$PN"2"50;
"A"
$PN"1"51;
%"Q_RES"
"2","(-5675,1225)","2","pure_quanta","I8";
;
PART_NUMBER"CS00002JB13"
PACK_TYPE"0402LF"
VALUE"0"
TOLERANCE"5%"
MATERIAL"CHIP"
WATTAGE"1/16W"
LOCATION"PR171"
CDS_LIB"pure_quanta"
LOCATION"PR171"
$SEC"1"
CDS_SEC"1";
"A"
$PN"1"96;
"B"
$PN"2"30;
%"Q_RES"
"1","(-4800,5400)","0","pure_quanta","I80";
;
PART_NUMBER"CS03322FB03"
TOLERANCE"1%"
MATERIAL"CHIP"
VALUE"33.2"
WATTAGE"1/16W"
PACK_TYPE"0402LF"
LOCATION"R2371"
CDS_LIB"pure_quanta"
LOCATION"R2371"
$SEC"1"
CDS_SEC"1";
"B"
$PN"2"54;
"A"
$PN"1"94;
%"VCC15"
"1","(-4500,5675)","0","logical_power","I81";
;
HDL_POWER"P3V3_AUX"
CDS_LIB"logical_power";
"A"5;
%"Q_CAP"
"2","(-4300,6275)","0","pure_quanta","I82";
;
PART_NUMBER"TMP_QCH21006JB10"
MATERIAL"X7R"
PACK_TYPE"0402"
VALUE"1000PF"
VOLTAGE"50V"
TOLERANCE"5%"
LOCATION"C3267"
CDS_LIB"pure_quanta"
LOCATION"C3267"
$SEC"1"
CDS_SEC"1";
"A"
$PN"1"74;
"B"
$PN"2"17;
%"UNIVERSAL_GND"
"1","(-3575,6275)","1","logical_power","I83";
;
CDS_LIB"logical_power"
HDL_POWER"GND";
"A"17;
%"Q_CAP"
"2","(-4275,6700)","0","pure_quanta","I84";
;
PART_NUMBER"TMP_QCH21006JB10"
MATERIAL"EMPTY"
VOLTAGE"50V"
VALUE"1000PF"
TOLERANCE"5%"
PACK_TYPE"0402"
LOCATION"C3266"
CDS_LIB"pure_quanta"
LOCATION"C3266"
$SEC"1"
CDS_SEC"1";
"A"
$PN"1"73;
"B"
$PN"2"16;
%"UNIVERSAL_GND"
"1","(-3575,6700)","1","logical_power","I85";
;
CDS_LIB"logical_power"
HDL_POWER"GND";
"A"16;
%"Q_CAP"
"1","(-1500,5875)","0","pure_quanta","I86";
;
PART_NUMBER"CH6101MEB03"
TOLERANCE"20%"
MATERIAL"X6S"
PACK_TYPE"C0402"
VOLTAGE"6.3V"
VALUE"10UF"
LOCATION"PC335"
CDS_LIB"pure_quanta"
LOCATION"PC335"
$SEC"1"
CDS_SEC"1";
"B"
$PN"2"12;
"A"
$PN"1"34;
%"Q_CAP"
"1","(-1100,5875)","0","pure_quanta","I87";
;
PART_NUMBER"CH5103KEB01"
VOLTAGE"16V"
TOLERANCE"10%"
MATERIAL"X6S"
PACK_TYPE"C0402"
VALUE"1UF"
LOCATION"PC1173"
CDS_LIB"pure_quanta"
$SEC"1"
CDS_SEC"1";
"B"
$PN"2"12;
"A"
$PN"1"34;
%"Q_CAP"
"1","(-1450,6350)","0","pure_quanta","I88";
;
PART_NUMBER"CH4104K1B00"
PACK_TYPE"0402"
MATERIAL"EMPTY"
TOLERANCE"10%"
VOLTAGE"25V"
VALUE"0.1UF"
LOCATION"PC334"
CDS_LIB"pure_quanta"
LOCATION"PC334"
$SEC"1"
CDS_SEC"1";
"B"
$PN"2"11;
"A"
$PN"1"55;
%"Q_CAP"
"1","(-1100,6350)","0","pure_quanta","I89";
;
PART_NUMBER"CH5103KEB01"
VOLTAGE"16V"
VALUE"1UF"
PACK_TYPE"C0402"
TOLERANCE"10%"
MATERIAL"X6S"
LOCATION"PC337"
CDS_LIB"pure_quanta"
LOCATION"PC337"
$SEC"1"
CDS_SEC"1";
"B"
$PN"2"11;
"A"
$PN"1"55;
%"UNIVERSAL_GND"
"1","(-5675,1000)","0","logical_power","I9";
;
CDS_LIB"logical_power"
HDL_POWER"GND";
"A"30;
END.
